# TIMECARD (Time Appliance Project (Time Card)) — schematic netlist excerpt (pin names and nets, part order shuffled) for the footprints in the layout excerpt that follows; sources: Cadence DE-HDL packaged netlist, KiCad conversion of R4006-B0001-02_R01.brd

DS6  OPTICAL  pkg SMC_DS_063X031_V4  page 26 : A = UNNAMED_14_OPTICAL_I140_A ; C = SG
R112  RESISTOR  33OHM 1%  pkg SMC_0402R_H016  page 22 : \1\ = DBG_UART_GPS_TXD ; \2\ = GPS_UART_TXD

(kicad_pcb
	(version 20260206)
	(generator "pcbnew")
	(generator_version "10.0")
	(general
		(thickness 1.6)
		(legacy_teardrops no)
	)
	(paper "A4")
	(title_block
		(title "timecard-production-celestica-r4006 — R4006-B0001-02_R01.brd")
		(comment 1 "Time Appliance Project (Time Card) / footprints 239-240 of 1113")
	)
	(layers
		(0 "F.Cu" signal "TOP")
		(4 "In1.Cu" signal "L02_GND1")
		(6 "In2.Cu" signal "L03_SIG1")
		(8 "In3.Cu" signal "L04_GND2")
		(10 "In4.Cu" signal "L05_VCC1")
		(12 "In5.Cu" signal "L06_VCC2")
		(14 "In6.Cu" signal "L07_GND3")
		(16 "In7.Cu" signal "L08_SIG2")
		(18 "In8.Cu" signal "L09_GND4")
		(2 "B.Cu" signal "BOTTOM")
		(9 "F.Adhes" user "F.Adhesive")
		(11 "B.Adhes" user "B.Adhesive")
		(13 "F.Paste" user "Package Geometry/Pastemask Top")
		(15 "B.Paste" user "Package Geometry/Pastemask Bottom")
		(5 "F.SilkS" user "Ref Des/Silkscreen Top")
		(7 "B.SilkS" user "Ref Des/Silkscreen Bottom")
		(1 "F.Mask" user "Board Geometry/Soldermask Top")
		(3 "B.Mask" user "Board Geometry/Soldermask Bottom")
		(17 "Dwgs.User" user "User.Drawings")
		(19 "Cmts.User" user "User.Comments")
		(21 "Eco1.User" user "User.Eco1")
		(23 "Eco2.User" user "User.Eco2")
		(25 "Edge.Cuts" user "Board Geometry/Outline")
		(27 "Margin" user)
		(31 "F.CrtYd" user "Package Geometry/Place Bound Top")
		(29 "B.CrtYd" user "Package Geometry/Place Bound Bottom")
		(35 "F.Fab" user "Ref Des/Assembly Top")
		(33 "B.Fab" user "Ref Des/Assembly Bottom")
	)
	(footprint ""
		(layer "F.Cu")
		(at 126.619 -89.535 90)
		(property "Reference" "R112"
			(at -3.429 0.54737 90)
			(unlocked yes)
			(layer "F.SilkS")
			(effects
				(font
					(size 0.7874 0.5842)
					(thickness 0.1524)
				)
			)
		)
		(property "Value" "VAL*"
			(at 0.02032 2.13233 90)
			(unlocked yes)
			(layer "F.Fab")
			(hide yes)
			(effects
				(font
					(size 0.7874 0.5842)
					(thickness 0.1524)
				)
			)
		)
		(property "Tolerance" "TOL*"
			(at 0.044704 3.05435 90)
			(unlocked yes)
			(layer "Cmts.User")
			(hide yes)
			(effects
				(font
					(size 0.7874 0.5842)
					(thickness 0.1524)
				)
			)
		)
		(property "User Part Number" "PARTNUM*"
			(at 0.02032 4.024884 90)
			(unlocked yes)
			(layer "Cmts.User")
			(hide yes)
			(effects
				(font
					(size 0.7874 0.5842)
					(thickness 0.1524)
				)
			)
		)
		(property "Device Type" "RESISTOR-G155-133R0-01,33OHM,1%"
			(at 0.008382 1.210564 90)
			(unlocked yes)
			(layer "F.Fab")
			(hide yes)
			(effects
				(font
					(size 0.7874 0.5842)
					(thickness 0.1524)
				)
			)
		)
		(duplicate_pad_numbers_are_jumpers no)
		(fp_line
			(start 1.143 -0.5588)
			(end -1.143 -0.5588)
			(stroke
				(width 0.1)
				(type default)
			)
			(layer "F.SilkS")
		)
		(fp_line
			(start -1.143 -0.5588)
			(end -1.143 0.5588)
			(stroke
				(width 0.1)
				(type default)
			)
			(layer "F.SilkS")
		)
		(fp_line
			(start 1.143 0.5588)
			(end 1.143 -0.5588)
			(stroke
				(width 0.1)
				(type default)
			)
			(layer "F.SilkS")
		)
		(fp_line
			(start -1.143 0.5588)
			(end 1.143 0.5588)
			(stroke
				(width 0.1)
				(type default)
			)
			(layer "F.SilkS")
		)
		(fp_rect
			(start -1.143 0.5588)
			(end 1.143 -0.5588)
			(stroke
				(width 0)
				(type default)
			)
			(fill no)
			(layer "F.CrtYd")
		)
		(fp_line
			(start 0.508 -0.3048)
			(end -0.508 -0.3048)
			(stroke
				(width 0.1)
				(type default)
			)
			(layer "F.Fab")
		)
		(fp_line
			(start -0.508 -0.3048)
			(end -0.508 0.3048)
			(stroke
				(width 0.1)
				(type default)
			)
			(layer "F.Fab")
		)
		(fp_line
			(start 0.508 0.3048)
			(end 0.508 -0.3048)
			(stroke
				(width 0.1)
				(type default)
			)
			(layer "F.Fab")
		)
		(fp_line
			(start -0.508 0.3048)
			(end 0.508 0.3048)
			(stroke
				(width 0.1)
				(type default)
			)
			(layer "F.Fab")
		)
		(pad "1" smd rect
			(at -0.5334 0 90)
			(size 0.7112 0.6096)
			(layers "F.Cu" "F.Mask" "F.Paste")
			(net "DBG_UART_GPS_TXD")
		)
		(pad "2" smd rect
			(at 0.5334 0 90)
			(size 0.7112 0.6096)
			(layers "F.Cu" "F.Mask" "F.Paste")
			(net "GPS_UART_TXD")
		)
		(zone
			(layer "F.Cu")
			(hatch none 0.5)
			(connect_pads
				(clearance 0)
			)
			(min_thickness 0.25)
			(keepout
				(tracks allowed)
				(vias not_allowed)
				(pads allowed)
				(copperpour not_allowed)
				(footprints allowed)
			)
			(placement
				(enabled no)
				(sheetname "")
			)
			(fill
				(thermal_gap 0.5)
				(thermal_bridge_width 0.5)
				(island_removal_mode 0)
			)
			(polygon
				(pts
					(xy 126.9238 -89.4588) (xy 126.9238 -89.6112) (xy 126.3142 -89.6112) (xy 126.3142 -89.4588)
				)
			)
		)
	)
	(footprint ""
		(layer "F.Cu")
		(at 138.050016 -104.350058 -90)
		(property "Reference" "DS6"
			(at 0.845058 1.993646 90)
			(unlocked yes)
			(layer "F.SilkS")
			(effects
				(font
					(size 0.7874 0.5842)
					(thickness 0.1524)
				)
			)
		)
		(property "Value" ""
			(at 0 0 270)
			(layer "F.Fab")
			(effects
				(font
					(size 1.27 1.27)
				)
			)
		)
		(property "Device Type" "OPTICAL-G170-10143-01"
			(at 0.1778 1.483081 270)
			(unlocked yes)
			(layer "F.Fab")
			(hide yes)
			(effects
				(font
					(size 0.786892 0.583946)
					(thickness 0.000001)
				)
			)
		)
		(property "User Part Number" "PARTNUM*"
			(at 0.1778 2.422881 270)
			(unlocked yes)
			(layer "Cmts.User")
			(hide yes)
			(effects
				(font
					(size 0.786892 0.583946)
					(thickness 0.000001)
				)
			)
		)
		(duplicate_pad_numbers_are_jumpers no)
		(fp_line
			(start -0.8128 1.8542)
			(end -2.0828 1.8542)
			(stroke
				(width 0.1)
				(type default)
			)
			(layer "F.SilkS")
		)
		(fp_line
			(start -1.4478 1.2192)
			(end -1.4478 2.4892)
			(stroke
				(width 0.1)
				(type default)
			)
			(layer "F.SilkS")
		)
		(fp_line
			(start -1.397508 0.704088)
			(end -1.397508 -0.704088)
			(stroke
				(width 0.1)
				(type default)
			)
			(layer "F.SilkS")
		)
		(fp_line
			(start 1.397508 0.704088)
			(end -1.397508 0.704088)
			(stroke
				(width 0.1)
				(type default)
			)
			(layer "F.SilkS")
		)
		(fp_line
			(start -1.397508 -0.704088)
			(end 1.397508 -0.704088)
			(stroke
				(width 0.1)
				(type default)
			)
			(layer "F.SilkS")
		)
		(fp_line
			(start 1.397508 -0.704088)
			(end 1.397508 0.704088)
			(stroke
				(width 0.1)
				(type default)
			)
			(layer "F.SilkS")
		)
		(fp_rect
			(start 1.905508 0.704088)
			(end 1.397508 -0.704088)
			(stroke
				(width 0)
				(type default)
			)
			(fill yes)
			(layer "F.SilkS")
		)
		(fp_rect
			(start 1.905508 0.958088)
			(end -1.651508 -0.958088)
			(stroke
				(width 0)
				(type default)
			)
			(fill no)
			(layer "F.CrtYd")
		)
		(fp_line
			(start -1.1938 1.4732)
			(end -2.4638 1.4732)
			(stroke
				(width 0.1)
				(type default)
			)
			(layer "F.Fab")
		)
		(fp_line
			(start -1.8288 0.8382)
			(end -1.8288 2.1082)
			(stroke
				(width 0.1)
				(type default)
			)
			(layer "F.Fab")
		)
		(fp_line
			(start -0.850138 0.450088)
			(end 0.850138 0.450088)
			(stroke
				(width 0.1)
				(type default)
			)
			(layer "F.Fab")
		)
		(fp_line
			(start 0.850138 0.450088)
			(end 0.850138 -0.450088)
			(stroke
				(width 0.1)
				(type default)
			)
			(layer "F.Fab")
		)
		(fp_line
			(start -0.850138 -0.450088)
			(end -0.850138 0.450088)
			(stroke
				(width 0.1)
				(type default)
			)
			(layer "F.Fab")
		)
		(fp_line
			(start 0.850138 -0.450088)
			(end -0.850138 -0.450088)
			(stroke
				(width 0.1)
				(type default)
			)
			(layer "F.Fab")
		)
		(fp_rect
			(start 0.850138 0.450088)
			(end 0.342138 -0.450088)
			(stroke
				(width 0)
				(type default)
			)
			(fill yes)
			(layer "F.Fab")
		)
		(fp_text user "A"
			(at -0.774192 1.652016 0)
			(unlocked yes)
			(layer "F.SilkS")
			(effects
				(font
					(size 0.635 0.4064)
					(thickness 0.1524)
				)
			)
		)
		(fp_text user "C"
			(at 1.892808 1.271016 0)
			(unlocked yes)
			(layer "F.SilkS")
			(effects
				(font
					(size 0.635 0.4064)
					(thickness 0.1524)
				)
			)
		)
		(fp_text user "A"
			(at -1.020572 0.890016 0)
			(unlocked yes)
			(layer "F.Fab")
			(effects
				(font
					(size 0.7874 0.5842)
					(thickness 0.1524)
				)
			)
		)
		(fp_text user "C"
			(at 1.773428 0.128016 0)
			(unlocked yes)
			(layer "F.Fab")
			(effects
				(font
					(size 0.7874 0.5842)
					(thickness 0.1524)
				)
			)
		)
		(pad "A" smd rect
			(at -0.749808 0 270)
			(size 0.7874 0.7874)
			(layers "F.Cu" "F.Mask" "F.Paste")
			(net "UNNAMED_14_OPTICAL_I140_A")
		)
		(pad "C" smd rect
			(at 0.749808 0 270)
			(size 0.7874 0.7874)
			(layers "F.Cu" "F.Mask" "F.Paste")
			(net "SG")
		)
	)
)
